# T6G (Grand Teton) — schematic netlist excerpt (pin names and nets, part order shuffled) for the footprints in the layout excerpt that follows; sources: Cadence DE-HDL packaged netlist, KiCad conversion of 04192023_DAF0TMB3IC0_F0TG_MB_C_brd_V02_OCP.brd

C2174  Q_CAP  22UF 4V 20% X6S  pkg C0402  page 69 : A = PVDDCR_CPU0_P0 ; B = GND
R829  Q_RES  0 5% CHIP  pkg 0201LF  page 185 : A = SMB_RT_CPU0_P1_ROM_MUX_2D_R_SCL ; B = SMB_RT_CPU0_P1_ROM_MUX_2D_SCL
C2425  Q_CAP  22UF 4V 20% X6S  pkg C0402  page 74 : A = PVDDCR_SOC_P1 ; B = GND

(kicad_pcb
	(version 20260206)
	(generator "pcbnew")
	(generator_version "10.0")
	(general
		(thickness 1.6)
		(legacy_teardrops no)
	)
	(paper "A4")
	(title_block
		(title "04192023_DAF0TMB3IC0_F0TG_MB_C_brd_V02_OCP.brd")
		(comment 1 "Grand Teton / footprints 7224-7226 of 8354")
	)
	(layers
		(0 "F.Cu" signal "TOP")
		(4 "In1.Cu" signal "GND")
		(6 "In2.Cu" signal "IN1")
		(8 "In3.Cu" signal "GND1")
		(10 "In4.Cu" signal "IN2")
		(12 "In5.Cu" signal "GND2")
		(14 "In6.Cu" signal "IN3")
		(16 "In7.Cu" signal "GND3")
		(18 "In8.Cu" signal "VCC")
		(20 "In9.Cu" signal "VCC1")
		(22 "In10.Cu" signal "GND4")
		(24 "In11.Cu" signal "IN4")
		(26 "In12.Cu" signal "GND5")
		(28 "In13.Cu" signal "IN5")
		(30 "In14.Cu" signal "GND6")
		(32 "In15.Cu" signal "IN6")
		(34 "In16.Cu" signal "GND7")
		(2 "B.Cu" signal "BOTTOM")
		(9 "F.Adhes" user "F.Adhesive")
		(11 "B.Adhes" user "B.Adhesive")
		(13 "F.Paste" user "Package Geometry/Pastemask Top")
		(15 "B.Paste" user "Package Geometry/Pastemask Bottom")
		(5 "F.SilkS" user "Ref Des/Silkscreen Top")
		(7 "B.SilkS" user "Ref Des/Silkscreen Bottom")
		(1 "F.Mask" user "Board Geometry/Soldermask Top")
		(3 "B.Mask" user "Board Geometry/Soldermask Bottom")
		(17 "Dwgs.User" user "User.Drawings")
		(19 "Cmts.User" user "User.Comments")
		(21 "Eco1.User" user "User.Eco1")
		(23 "Eco2.User" user "User.Eco2")
		(25 "Edge.Cuts" user "Board Geometry/Outline")
		(27 "Margin" user)
		(31 "F.CrtYd" user "Package Geometry/Place Bound Top")
		(29 "B.CrtYd" user "Package Geometry/Place Bound Bottom")
		(35 "F.Fab" user "Ref Des/Assembly Top")
		(33 "B.Fab" user "Ref Des/Assembly Bottom")
	)
	(footprint ""
		(layer "B.Cu")
		(at 125.389386 -258.830318)
		(property "Reference" "C2425"
			(at 0 0 0)
			(layer "B.SilkS")
			(hide yes)
			(effects
				(font
					(size 1.27 1.27)
				)
				(justify mirror)
			)
		)
		(property "Value" ""
			(at 0 0 0)
			(layer "B.Fab")
			(effects
				(font
					(size 1.27 1.27)
				)
				(justify mirror)
			)
		)
		(duplicate_pad_numbers_are_jumpers no)
		(fp_line
			(start -0.7874 -0.4064)
			(end -0.7874 0.4064)
			(stroke
				(width 0.1524)
				(type default)
			)
			(layer "B.SilkS")
		)
		(fp_line
			(start -0.7874 0.4064)
			(end 0.7874 0.4064)
			(stroke
				(width 0.1524)
				(type default)
			)
			(layer "B.SilkS")
		)
		(fp_line
			(start 0.7874 -0.4064)
			(end -0.7874 -0.4064)
			(stroke
				(width 0.1524)
				(type default)
			)
			(layer "B.SilkS")
		)
		(fp_line
			(start 0.7874 0.4064)
			(end 0.7874 -0.4064)
			(stroke
				(width 0.1524)
				(type default)
			)
			(layer "B.SilkS")
		)
		(fp_line
			(start -0.67945 -0.3048)
			(end -0.67945 0.3048)
			(stroke
				(width 0.1)
				(type default)
			)
			(layer "B.Fab")
		)
		(fp_line
			(start -0.67945 0.3048)
			(end -0.120396 0.3048)
			(stroke
				(width 0.1)
				(type default)
			)
			(layer "B.Fab")
		)
		(fp_line
			(start -0.12065 -0.3048)
			(end -0.67945 -0.3048)
			(stroke
				(width 0.1)
				(type default)
			)
			(layer "B.Fab")
		)
		(fp_line
			(start -0.12065 -0.2794)
			(end -0.12065 -0.3048)
			(stroke
				(width 0.1)
				(type default)
			)
			(layer "B.Fab")
		)
		(fp_line
			(start -0.120396 0.2794)
			(end 0.12065 0.2794)
			(stroke
				(width 0.1)
				(type default)
			)
			(layer "B.Fab")
		)
		(fp_line
			(start -0.120396 0.3048)
			(end -0.120396 0.2794)
			(stroke
				(width 0.1)
				(type default)
			)
			(layer "B.Fab")
		)
		(fp_line
			(start 0.12065 -0.305054)
			(end 0.12065 -0.2794)
			(stroke
				(width 0.1)
				(type default)
			)
			(layer "B.Fab")
		)
		(fp_line
			(start 0.12065 -0.2794)
			(end -0.12065 -0.2794)
			(stroke
				(width 0.1)
				(type default)
			)
			(layer "B.Fab")
		)
		(fp_line
			(start 0.12065 0.2794)
			(end 0.12065 0.3048)
			(stroke
				(width 0.1)
				(type default)
			)
			(layer "B.Fab")
		)
		(fp_line
			(start 0.12065 0.3048)
			(end 0.67945 0.3048)
			(stroke
				(width 0.1)
				(type default)
			)
			(layer "B.Fab")
		)
		(fp_line
			(start 0.67945 -0.305054)
			(end 0.12065 -0.305054)
			(stroke
				(width 0.1)
				(type default)
			)
			(layer "B.Fab")
		)
		(fp_line
			(start 0.67945 0.3048)
			(end 0.67945 -0.305054)
			(stroke
				(width 0.1)
				(type default)
			)
			(layer "B.Fab")
		)
		(pad "1" smd circle
			(at 0.40005 0 180)
			(size 0 0)
			(layers "B.Cu" "B.Mask" "B.Paste")
			(net "PVDDCR_SOC_P1")
		)
		(pad "2" smd circle
			(at -0.40005 0 180)
			(size 0 0)
			(layers "B.Cu" "B.Mask" "B.Paste")
			(net "GND")
		)
	)
	(footprint ""
		(layer "B.Cu")
		(at 364.439454 -248.47931)
		(property "Reference" "C2174"
			(at 0 0 0)
			(layer "B.SilkS")
			(hide yes)
			(effects
				(font
					(size 1.27 1.27)
				)
				(justify mirror)
			)
		)
		(property "Value" ""
			(at 0 0 0)
			(layer "B.Fab")
			(effects
				(font
					(size 1.27 1.27)
				)
				(justify mirror)
			)
		)
		(duplicate_pad_numbers_are_jumpers no)
		(fp_line
			(start -0.7874 -0.4064)
			(end -0.7874 0.4064)
			(stroke
				(width 0.1524)
				(type default)
			)
			(layer "B.SilkS")
		)
		(fp_line
			(start -0.7874 0.4064)
			(end 0.7874 0.4064)
			(stroke
				(width 0.1524)
				(type default)
			)
			(layer "B.SilkS")
		)
		(fp_line
			(start 0.7874 -0.4064)
			(end -0.7874 -0.4064)
			(stroke
				(width 0.1524)
				(type default)
			)
			(layer "B.SilkS")
		)
		(fp_line
			(start 0.7874 0.4064)
			(end 0.7874 -0.4064)
			(stroke
				(width 0.1524)
				(type default)
			)
			(layer "B.SilkS")
		)
		(fp_line
			(start -0.67945 -0.3048)
			(end -0.67945 0.3048)
			(stroke
				(width 0.1)
				(type default)
			)
			(layer "B.Fab")
		)
		(fp_line
			(start -0.67945 0.3048)
			(end -0.120396 0.3048)
			(stroke
				(width 0.1)
				(type default)
			)
			(layer "B.Fab")
		)
		(fp_line
			(start -0.12065 -0.3048)
			(end -0.67945 -0.3048)
			(stroke
				(width 0.1)
				(type default)
			)
			(layer "B.Fab")
		)
		(fp_line
			(start -0.12065 -0.2794)
			(end -0.12065 -0.3048)
			(stroke
				(width 0.1)
				(type default)
			)
			(layer "B.Fab")
		)
		(fp_line
			(start -0.120396 0.2794)
			(end 0.12065 0.2794)
			(stroke
				(width 0.1)
				(type default)
			)
			(layer "B.Fab")
		)
		(fp_line
			(start -0.120396 0.3048)
			(end -0.120396 0.2794)
			(stroke
				(width 0.1)
				(type default)
			)
			(layer "B.Fab")
		)
		(fp_line
			(start 0.12065 -0.305054)
			(end 0.12065 -0.2794)
			(stroke
				(width 0.1)
				(type default)
			)
			(layer "B.Fab")
		)
		(fp_line
			(start 0.12065 -0.2794)
			(end -0.12065 -0.2794)
			(stroke
				(width 0.1)
				(type default)
			)
			(layer "B.Fab")
		)
		(fp_line
			(start 0.12065 0.2794)
			(end 0.12065 0.3048)
			(stroke
				(width 0.1)
				(type default)
			)
			(layer "B.Fab")
		)
		(fp_line
			(start 0.12065 0.3048)
			(end 0.67945 0.3048)
			(stroke
				(width 0.1)
				(type default)
			)
			(layer "B.Fab")
		)
		(fp_line
			(start 0.67945 -0.305054)
			(end 0.12065 -0.305054)
			(stroke
				(width 0.1)
				(type default)
			)
			(layer "B.Fab")
		)
		(fp_line
			(start 0.67945 0.3048)
			(end 0.67945 -0.305054)
			(stroke
				(width 0.1)
				(type default)
			)
			(layer "B.Fab")
		)
		(pad "1" smd circle
			(at 0.40005 0 180)
			(size 0 0)
			(layers "B.Cu" "B.Mask" "B.Paste")
			(net "PVDDCR_CPU0_P0")
		)
		(pad "2" smd circle
			(at -0.40005 0 180)
			(size 0 0)
			(layers "B.Cu" "B.Mask" "B.Paste")
			(net "GND")
		)
	)
	(footprint ""
		(layer "B.Cu")
		(at 255.905 -338.51596 180)
		(property "Reference" "R829"
			(at 0 0 0)
			(layer "B.SilkS")
			(hide yes)
			(effects
				(font
					(size 1.27 1.27)
				)
				(justify mirror)
			)
		)
		(property "Value" ""
			(at 0 0 0)
			(layer "B.Fab")
			(effects
				(font
					(size 1.27 1.27)
				)
				(justify mirror)
			)
		)
		(duplicate_pad_numbers_are_jumpers no)
		(fp_line
			(start 0.32512 0.175006)
			(end 0.32512 -0.175006)
			(stroke
				(width 0.1)
				(type default)
			)
			(layer "B.Fab")
		)
		(fp_line
			(start 0.32512 -0.175006)
			(end -0.32512 -0.175006)
			(stroke
				(width 0.1)
				(type default)
			)
			(layer "B.Fab")
		)
		(fp_line
			(start -0.32512 0.175006)
			(end 0.32512 0.175006)
			(stroke
				(width 0.1)
				(type default)
			)
			(layer "B.Fab")
		)
		(fp_line
			(start -0.32512 -0.175006)
			(end -0.32512 0.175006)
			(stroke
				(width 0.1)
				(type default)
			)
			(layer "B.Fab")
		)
		(pad "1" smd rect
			(at 0.2667 0)
			(size 0.3048 0.381)
			(layers "B.Cu" "B.Mask" "B.Paste")
			(net "SMB_RT_CPU0_P1_ROM_MUX_2D_R_SCL")
		)
		(pad "2" smd rect
			(at -0.2667 0 180)
			(size 0.3048 0.381)
			(layers "B.Cu" "B.Mask" "B.Paste")
			(net "SMB_RT_CPU0_P1_ROM_MUX_2D_SCL")
		)
	)
)
